(kicad_pcb
	(version 20260206)
	(generator "pcbnew")
	(generator_version "10.0")
	(general
		(thickness 1.6)
		(legacy_teardrops no)
	)
	(paper "A4")
	(title_block
		(title "04192023_DAF0TMB3IC0_F0TG_MB_C_brd_V02_OCP.brd")
		(comment 1 "Grand Teton / footprints 2153-2159 of 8354")
	)
	(layers
		(0 "F.Cu" signal "TOP")
		(4 "In1.Cu" signal "GND")
		(6 "In2.Cu" signal "IN1")
		(8 "In3.Cu" signal "GND1")
		(10 "In4.Cu" signal "IN2")
		(12 "In5.Cu" signal "GND2")
		(14 "In6.Cu" signal "IN3")
		(16 "In7.Cu" signal "GND3")
		(18 "In8.Cu" signal "VCC")
		(20 "In9.Cu" signal "VCC1")
		(22 "In10.Cu" signal "GND4")
		(24 "In11.Cu" signal "IN4")
		(26 "In12.Cu" signal "GND5")
		(28 "In13.Cu" signal "IN5")
		(30 "In14.Cu" signal "GND6")
		(32 "In15.Cu" signal "IN6")
		(34 "In16.Cu" signal "GND7")
		(2 "B.Cu" signal "BOTTOM")
		(9 "F.Adhes" user "F.Adhesive")
		(11 "B.Adhes" user "B.Adhesive")
		(13 "F.Paste" user "Package Geometry/Pastemask Top")
		(15 "B.Paste" user "Package Geometry/Pastemask Bottom")
		(5 "F.SilkS" user "Ref Des/Silkscreen Top")
		(7 "B.SilkS" user "Ref Des/Silkscreen Bottom")
		(1 "F.Mask" user "Board Geometry/Soldermask Top")
		(3 "B.Mask" user "Board Geometry/Soldermask Bottom")
		(17 "Dwgs.User" user "User.Drawings")
		(19 "Cmts.User" user "User.Comments")
		(21 "Eco1.User" user "User.Eco1")
		(23 "Eco2.User" user "User.Eco2")
		(25 "Edge.Cuts" user "Board Geometry/Outline")
		(27 "Margin" user)
		(31 "F.CrtYd" user "Package Geometry/Place Bound Top")
		(29 "B.CrtYd" user "Package Geometry/Place Bound Bottom")
		(35 "F.Fab" user "Ref Des/Assembly Top")
		(33 "B.Fab" user "Ref Des/Assembly Bottom")
	)
	(footprint ""
		(layer "F.Cu")
		(at 310.48198 -351.368106 -90)
		(property "Reference" "PC121"
			(at 0 0 270)
			(layer "F.SilkS")
			(hide yes)
			(effects
				(font
					(size 1.27 1.27)
				)
			)
		)
		(property "Value" ""
			(at 0 0 270)
			(layer "F.Fab")
			(effects
				(font
					(size 1.27 1.27)
				)
			)
		)
		(duplicate_pad_numbers_are_jumpers no)
		(fp_line
			(start -0.7874 0.4064)
			(end -0.7874 -0.4064)
			(stroke
				(width 0.1524)
				(type default)
			)
			(layer "F.SilkS")
		)
		(fp_line
			(start 0.7874 0.4064)
			(end -0.7874 0.4064)
			(stroke
				(width 0.1524)
				(type default)
			)
			(layer "F.SilkS")
		)
		(fp_line
			(start -0.7874 -0.4064)
			(end 0.7874 -0.4064)
			(stroke
				(width 0.1524)
				(type default)
			)
			(layer "F.SilkS")
		)
		(fp_line
			(start 0.7874 -0.4064)
			(end 0.7874 0.4064)
			(stroke
				(width 0.1524)
				(type default)
			)
			(layer "F.SilkS")
		)
		(fp_line
			(start -0.67945 0.3048)
			(end -0.67945 -0.305054)
			(stroke
				(width 0.1)
				(type default)
			)
			(layer "F.Fab")
		)
		(fp_line
			(start -0.12065 0.3048)
			(end -0.67945 0.3048)
			(stroke
				(width 0.1)
				(type default)
			)
			(layer "F.Fab")
		)
		(fp_line
			(start 0.120396 0.3048)
			(end 0.120396 0.2794)
			(stroke
				(width 0.1)
				(type default)
			)
			(layer "F.Fab")
		)
		(fp_line
			(start 0.67945 0.3048)
			(end 0.120396 0.3048)
			(stroke
				(width 0.1)
				(type default)
			)
			(layer "F.Fab")
		)
		(fp_line
			(start -0.12065 0.2794)
			(end -0.12065 0.3048)
			(stroke
				(width 0.1)
				(type default)
			)
			(layer "F.Fab")
		)
		(fp_line
			(start 0.120396 0.2794)
			(end -0.12065 0.2794)
			(stroke
				(width 0.1)
				(type default)
			)
			(layer "F.Fab")
		)
		(fp_line
			(start -0.12065 -0.2794)
			(end 0.12065 -0.2794)
			(stroke
				(width 0.1)
				(type default)
			)
			(layer "F.Fab")
		)
		(fp_line
			(start 0.12065 -0.2794)
			(end 0.12065 -0.3048)
			(stroke
				(width 0.1)
				(type default)
			)
			(layer "F.Fab")
		)
		(fp_line
			(start 0.12065 -0.3048)
			(end 0.67945 -0.3048)
			(stroke
				(width 0.1)
				(type default)
			)
			(layer "F.Fab")
		)
		(fp_line
			(start 0.67945 -0.3048)
			(end 0.67945 0.3048)
			(stroke
				(width 0.1)
				(type default)
			)
			(layer "F.Fab")
		)
		(fp_line
			(start -0.67945 -0.305054)
			(end -0.12065 -0.305054)
			(stroke
				(width 0.1)
				(type default)
			)
			(layer "F.Fab")
		)
		(fp_line
			(start -0.12065 -0.305054)
			(end -0.12065 -0.2794)
			(stroke
				(width 0.1)
				(type default)
			)
			(layer "F.Fab")
		)
		(pad "1" smd circle
			(at -0.40005 0 270)
			(size 0 0)
			(layers "F.Cu" "F.Mask" "F.Paste")
			(net "SW_PVDDCR_CPU1_P0_BOOT4_R")
		)
		(pad "2" smd circle
			(at 0.40005 0 270)
			(size 0 0)
			(layers "F.Cu" "F.Mask" "F.Paste")
			(net "SW_PVDDCR_CPU1_P0_BOOTR4")
		)
	)
	(footprint ""
		(layer "F.Cu")
		(at 250.55957 -69.962522 180)
		(property "Reference" "R6049"
			(at 0 0 180)
			(layer "F.SilkS")
			(hide yes)
			(effects
				(font
					(size 1.27 1.27)
				)
			)
		)
		(property "Value" ""
			(at 0 0 180)
			(layer "F.Fab")
			(effects
				(font
					(size 1.27 1.27)
				)
			)
		)
		(duplicate_pad_numbers_are_jumpers no)
		(fp_line
			(start 0.7874 0.4064)
			(end -0.7874 0.4064)
			(stroke
				(width 0.1524)
				(type default)
			)
			(layer "F.SilkS")
		)
		(fp_line
			(start 0.7874 -0.4064)
			(end 0.7874 0.4064)
			(stroke
				(width 0.1524)
				(type default)
			)
			(layer "F.SilkS")
		)
		(fp_line
			(start -0.7874 0.4064)
			(end -0.7874 -0.4064)
			(stroke
				(width 0.1524)
				(type default)
			)
			(layer "F.SilkS")
		)
		(fp_line
			(start -0.7874 -0.4064)
			(end 0.7874 -0.4064)
			(stroke
				(width 0.1524)
				(type default)
			)
			(layer "F.SilkS")
		)
		(fp_line
			(start 0.67945 0.3048)
			(end 0.120396 0.3048)
			(stroke
				(width 0.1)
				(type default)
			)
			(layer "F.Fab")
		)
		(fp_line
			(start 0.67945 -0.3048)
			(end 0.67945 0.3048)
			(stroke
				(width 0.1)
				(type default)
			)
			(layer "F.Fab")
		)
		(fp_line
			(start 0.12065 -0.2794)
			(end 0.12065 -0.3048)
			(stroke
				(width 0.1)
				(type default)
			)
			(layer "F.Fab")
		)
		(fp_line
			(start 0.12065 -0.3048)
			(end 0.67945 -0.3048)
			(stroke
				(width 0.1)
				(type default)
			)
			(layer "F.Fab")
		)
		(fp_line
			(start 0.120396 0.3048)
			(end 0.120396 0.2794)
			(stroke
				(width 0.1)
				(type default)
			)
			(layer "F.Fab")
		)
		(fp_line
			(start 0.120396 0.2794)
			(end -0.12065 0.2794)
			(stroke
				(width 0.1)
				(type default)
			)
			(layer "F.Fab")
		)
		(fp_line
			(start -0.12065 0.3048)
			(end -0.67945 0.3048)
			(stroke
				(width 0.1)
				(type default)
			)
			(layer "F.Fab")
		)
		(fp_line
			(start -0.12065 0.2794)
			(end -0.12065 0.3048)
			(stroke
				(width 0.1)
				(type default)
			)
			(layer "F.Fab")
		)
		(fp_line
			(start -0.12065 -0.2794)
			(end 0.12065 -0.2794)
			(stroke
				(width 0.1)
				(type default)
			)
			(layer "F.Fab")
		)
		(fp_line
			(start -0.12065 -0.305054)
			(end -0.12065 -0.2794)
			(stroke
				(width 0.1)
				(type default)
			)
			(layer "F.Fab")
		)
		(fp_line
			(start -0.67945 0.3048)
			(end -0.67945 -0.305054)
			(stroke
				(width 0.1)
				(type default)
			)
			(layer "F.Fab")
		)
		(fp_line
			(start -0.67945 -0.305054)
			(end -0.12065 -0.305054)
			(stroke
				(width 0.1)
				(type default)
			)
			(layer "F.Fab")
		)
		(pad "1" smd circle
			(at -0.40005 0 180)
			(size 0 0)
			(layers "F.Cu" "F.Mask" "F.Paste")
			(net "P3V3_E1S_EN_0_R")
		)
		(pad "2" smd circle
			(at 0.40005 0 180)
			(size 0 0)
			(layers "F.Cu" "F.Mask" "F.Paste")
			(net "GND")
		)
	)
	(footprint ""
		(layer "F.Cu")
		(at 299.265594 -393.04468)
		(property "Reference" "R980"
			(at 0 0 0)
			(layer "F.SilkS")
			(hide yes)
			(effects
				(font
					(size 1.27 1.27)
				)
			)
		)
		(property "Value" ""
			(at 0 0 0)
			(layer "F.Fab")
			(effects
				(font
					(size 1.27 1.27)
				)
			)
		)
		(duplicate_pad_numbers_are_jumpers no)
		(fp_line
			(start -0.32512 -0.175006)
			(end 0.32512 -0.175006)
			(stroke
				(width 0.1)
				(type default)
			)
			(layer "F.Fab")
		)
		(fp_line
			(start -0.32512 0.175006)
			(end -0.32512 -0.175006)
			(stroke
				(width 0.1)
				(type default)
			)
			(layer "F.Fab")
		)
		(fp_line
			(start 0.32512 -0.175006)
			(end 0.32512 0.175006)
			(stroke
				(width 0.1)
				(type default)
			)
			(layer "F.Fab")
		)
		(fp_line
			(start 0.32512 0.175006)
			(end -0.32512 0.175006)
			(stroke
				(width 0.1)
				(type default)
			)
			(layer "F.Fab")
		)
		(pad "1" smd rect
			(at -0.2667 0)
			(size 0.3048 0.381)
			(layers "F.Cu" "F.Mask" "F.Paste")
			(net "GPIO3_RT_CPU0_P0")
		)
		(pad "2" smd rect
			(at 0.2667 0 180)
			(size 0.3048 0.381)
			(layers "F.Cu" "F.Mask" "F.Paste")
			(net "GND")
		)
	)
	(footprint ""
		(layer "F.Cu")
		(at 22.07768 -431.421794)
		(property "Reference" "R3109"
			(at 0 0 0)
			(layer "F.SilkS")
			(hide yes)
			(effects
				(font
					(size 1.27 1.27)
				)
			)
		)
		(property "Value" ""
			(at 0 0 0)
			(layer "F.Fab")
			(effects
				(font
					(size 1.27 1.27)
				)
			)
		)
		(duplicate_pad_numbers_are_jumpers no)
		(fp_line
			(start -0.7874 -0.4064)
			(end 0.7874 -0.4064)
			(stroke
				(width 0.1524)
				(type default)
			)
			(layer "F.SilkS")
		)
		(fp_line
			(start -0.7874 0.4064)
			(end -0.7874 -0.4064)
			(stroke
				(width 0.1524)
				(type default)
			)
			(layer "F.SilkS")
		)
		(fp_line
			(start 0.7874 -0.4064)
			(end 0.7874 0.4064)
			(stroke
				(width 0.1524)
				(type default)
			)
			(layer "F.SilkS")
		)
		(fp_line
			(start 0.7874 0.4064)
			(end -0.7874 0.4064)
			(stroke
				(width 0.1524)
				(type default)
			)
			(layer "F.SilkS")
		)
		(fp_line
			(start -0.67945 -0.305054)
			(end -0.12065 -0.305054)
			(stroke
				(width 0.1)
				(type default)
			)
			(layer "F.Fab")
		)
		(fp_line
			(start -0.67945 0.3048)
			(end -0.67945 -0.305054)
			(stroke
				(width 0.1)
				(type default)
			)
			(layer "F.Fab")
		)
		(fp_line
			(start -0.12065 -0.305054)
			(end -0.12065 -0.2794)
			(stroke
				(width 0.1)
				(type default)
			)
			(layer "F.Fab")
		)
		(fp_line
			(start -0.12065 -0.2794)
			(end 0.12065 -0.2794)
			(stroke
				(width 0.1)
				(type default)
			)
			(layer "F.Fab")
		)
		(fp_line
			(start -0.12065 0.2794)
			(end -0.12065 0.3048)
			(stroke
				(width 0.1)
				(type default)
			)
			(layer "F.Fab")
		)
		(fp_line
			(start -0.12065 0.3048)
			(end -0.67945 0.3048)
			(stroke
				(width 0.1)
				(type default)
			)
			(layer "F.Fab")
		)
		(fp_line
			(start 0.120396 0.2794)
			(end -0.12065 0.2794)
			(stroke
				(width 0.1)
				(type default)
			)
			(layer "F.Fab")
		)
		(fp_line
			(start 0.120396 0.3048)
			(end 0.120396 0.2794)
			(stroke
				(width 0.1)
				(type default)
			)
			(layer "F.Fab")
		)
		(fp_line
			(start 0.12065 -0.3048)
			(end 0.67945 -0.3048)
			(stroke
				(width 0.1)
				(type default)
			)
			(layer "F.Fab")
		)
		(fp_line
			(start 0.12065 -0.2794)
			(end 0.12065 -0.3048)
			(stroke
				(width 0.1)
				(type default)
			)
			(layer "F.Fab")
		)
		(fp_line
			(start 0.67945 -0.3048)
			(end 0.67945 0.3048)
			(stroke
				(width 0.1)
				(type default)
			)
			(layer "F.Fab")
		)
		(fp_line
			(start 0.67945 0.3048)
			(end 0.120396 0.3048)
			(stroke
				(width 0.1)
				(type default)
			)
			(layer "F.Fab")
		)
		(pad "1" smd circle
			(at -0.40005 0)
			(size 0 0)
			(layers "F.Cu" "F.Mask" "F.Paste")
			(net "SMB_1_BMC_GPU_SCL")
		)
		(pad "2" smd circle
			(at 0.40005 0)
			(size 0 0)
			(layers "F.Cu" "F.Mask" "F.Paste")
			(net "SMB_1_BMC_GPU_R_SCL")
		)
	)
	(footprint ""
		(layer "F.Cu")
		(at 244.327426 -285.631636)
		(property "Reference" "PC6501"
			(at 0 0 0)
			(layer "F.SilkS")
			(hide yes)
			(effects
				(font
					(size 1.27 1.27)
				)
			)
		)
		(property "Value" ""
			(at 0 0 0)
			(layer "F.Fab")
			(effects
				(font
					(size 1.27 1.27)
				)
			)
		)
		(duplicate_pad_numbers_are_jumpers no)
		(fp_line
			(start -1.524 -0.762)
			(end 1.524 -0.762)
			(stroke
				(width 0.1524)
				(type default)
			)
			(layer "F.SilkS")
		)
		(fp_line
			(start -1.524 0.762)
			(end -1.524 -0.762)
			(stroke
				(width 0.1524)
				(type default)
			)
			(layer "F.SilkS")
		)
		(fp_line
			(start 1.524 -0.762)
			(end 1.524 0.762)
			(stroke
				(width 0.1524)
				(type default)
			)
			(layer "F.SilkS")
		)
		(fp_line
			(start 1.524 0.762)
			(end -1.524 0.762)
			(stroke
				(width 0.1524)
				(type default)
			)
			(layer "F.SilkS")
		)
		(fp_line
			(start -1.1049 -0.724916)
			(end -1.1049 0.724916)
			(stroke
				(width 0.1)
				(type default)
			)
			(layer "F.Fab")
		)
		(fp_line
			(start -1.1049 0.724916)
			(end 1.1049 0.724916)
			(stroke
				(width 0.1)
				(type default)
			)
			(layer "F.Fab")
		)
		(fp_line
			(start 1.1049 -0.724916)
			(end -1.1049 -0.724916)
			(stroke
				(width 0.1)
				(type default)
			)
			(layer "F.Fab")
		)
		(fp_line
			(start 1.1049 0.724916)
			(end 1.1049 -0.724916)
			(stroke
				(width 0.1)
				(type default)
			)
			(layer "F.Fab")
		)
		(pad "1" smd rect
			(at -0.889 0 180)
			(size 1.016 1.27)
			(layers "F.Cu" "F.Mask" "F.Paste")
			(net "SW_P12V_AUX_P1V8_RETIMER_CPU0_FLT")
		)
		(pad "2" smd rect
			(at 0.889 0 180)
			(size 1.016 1.27)
			(layers "F.Cu" "F.Mask" "F.Paste")
			(net "GND")
		)
	)
	(footprint ""
		(layer "F.Cu")
		(at 180.777134 -56.352948 180)
		(property "Reference" "R178"
			(at 0 0 180)
			(layer "F.SilkS")
			(hide yes)
			(effects
				(font
					(size 1.27 1.27)
				)
			)
		)
		(property "Value" ""
			(at 0 0 180)
			(layer "F.Fab")
			(effects
				(font
					(size 1.27 1.27)
				)
			)
		)
		(duplicate_pad_numbers_are_jumpers no)
		(fp_line
			(start 0.7874 0.4064)
			(end -0.7874 0.4064)
			(stroke
				(width 0.1524)
				(type default)
			)
			(layer "F.SilkS")
		)
		(fp_line
			(start 0.7874 -0.4064)
			(end 0.7874 0.4064)
			(stroke
				(width 0.1524)
				(type default)
			)
			(layer "F.SilkS")
		)
		(fp_line
			(start -0.7874 0.4064)
			(end -0.7874 -0.4064)
			(stroke
				(width 0.1524)
				(type default)
			)
			(layer "F.SilkS")
		)
		(fp_line
			(start -0.7874 -0.4064)
			(end 0.7874 -0.4064)
			(stroke
				(width 0.1524)
				(type default)
			)
			(layer "F.SilkS")
		)
		(fp_line
			(start 0.67945 0.3048)
			(end 0.120396 0.3048)
			(stroke
				(width 0.1)
				(type default)
			)
			(layer "F.Fab")
		)
		(fp_line
			(start 0.67945 -0.3048)
			(end 0.67945 0.3048)
			(stroke
				(width 0.1)
				(type default)
			)
			(layer "F.Fab")
		)
		(fp_line
			(start 0.12065 -0.2794)
			(end 0.12065 -0.3048)
			(stroke
				(width 0.1)
				(type default)
			)
			(layer "F.Fab")
		)
		(fp_line
			(start 0.12065 -0.3048)
			(end 0.67945 -0.3048)
			(stroke
				(width 0.1)
				(type default)
			)
			(layer "F.Fab")
		)
		(fp_line
			(start 0.120396 0.3048)
			(end 0.120396 0.2794)
			(stroke
				(width 0.1)
				(type default)
			)
			(layer "F.Fab")
		)
		(fp_line
			(start 0.120396 0.2794)
			(end -0.12065 0.2794)
			(stroke
				(width 0.1)
				(type default)
			)
			(layer "F.Fab")
		)
		(fp_line
			(start -0.12065 0.3048)
			(end -0.67945 0.3048)
			(stroke
				(width 0.1)
				(type default)
			)
			(layer "F.Fab")
		)
		(fp_line
			(start -0.12065 0.2794)
			(end -0.12065 0.3048)
			(stroke
				(width 0.1)
				(type default)
			)
			(layer "F.Fab")
		)
		(fp_line
			(start -0.12065 -0.2794)
			(end 0.12065 -0.2794)
			(stroke
				(width 0.1)
				(type default)
			)
			(layer "F.Fab")
		)
		(fp_line
			(start -0.12065 -0.305054)
			(end -0.12065 -0.2794)
			(stroke
				(width 0.1)
				(type default)
			)
			(layer "F.Fab")
		)
		(fp_line
			(start -0.67945 0.3048)
			(end -0.67945 -0.305054)
			(stroke
				(width 0.1)
				(type default)
			)
			(layer "F.Fab")
		)
		(fp_line
			(start -0.67945 -0.305054)
			(end -0.12065 -0.305054)
			(stroke
				(width 0.1)
				(type default)
			)
			(layer "F.Fab")
		)
		(pad "1" smd circle
			(at -0.40005 0 180)
			(size 0 0)
			(layers "F.Cu" "F.Mask" "F.Paste")
			(net "P3V3_AUX")
		)
		(pad "2" smd circle
			(at 0.40005 0 180)
			(size 0 0)
			(layers "F.Cu" "F.Mask" "F.Paste")
			(net "PCIE_M2_SSD0_PRSNT_N")
		)
	)
	(footprint ""
		(layer "F.Cu")
		(at 37.211 -362.077 180)
		(property "Reference" "R8252"
			(at 0 0 180)
			(layer "F.SilkS")
			(hide yes)
			(effects
				(font
					(size 1.27 1.27)
				)
			)
		)
		(property "Value" ""
			(at 0 0 180)
			(layer "F.Fab")
			(effects
				(font
					(size 1.27 1.27)
				)
			)
		)
		(duplicate_pad_numbers_are_jumpers no)
		(fp_line
			(start 0.7874 0.4064)
			(end -0.7874 0.4064)
			(stroke
				(width 0.1524)
				(type default)
			)
			(layer "F.SilkS")
		)
		(fp_line
			(start 0.7874 -0.4064)
			(end 0.7874 0.4064)
			(stroke
				(width 0.1524)
				(type default)
			)
			(layer "F.SilkS")
		)
		(fp_line
			(start -0.7874 0.4064)
			(end -0.7874 -0.4064)
			(stroke
				(width 0.1524)
				(type default)
			)
			(layer "F.SilkS")
		)
		(fp_line
			(start -0.7874 -0.4064)
			(end 0.7874 -0.4064)
			(stroke
				(width 0.1524)
				(type default)
			)
			(layer "F.SilkS")
		)
		(fp_line
			(start 0.67945 0.3048)
			(end 0.120396 0.3048)
			(stroke
				(width 0.1)
				(type default)
			)
			(layer "F.Fab")
		)
		(fp_line
			(start 0.67945 -0.3048)
			(end 0.67945 0.3048)
			(stroke
				(width 0.1)
				(type default)
			)
			(layer "F.Fab")
		)
		(fp_line
			(start 0.12065 -0.2794)
			(end 0.12065 -0.3048)
			(stroke
				(width 0.1)
				(type default)
			)
			(layer "F.Fab")
		)
		(fp_line
			(start 0.12065 -0.3048)
			(end 0.67945 -0.3048)
			(stroke
				(width 0.1)
				(type default)
			)
			(layer "F.Fab")
		)
		(fp_line
			(start 0.120396 0.3048)
			(end 0.120396 0.2794)
			(stroke
				(width 0.1)
				(type default)
			)
			(layer "F.Fab")
		)
		(fp_line
			(start 0.120396 0.2794)
			(end -0.12065 0.2794)
			(stroke
				(width 0.1)
				(type default)
			)
			(layer "F.Fab")
		)
		(fp_line
			(start -0.12065 0.3048)
			(end -0.67945 0.3048)
			(stroke
				(width 0.1)
				(type default)
			)
			(layer "F.Fab")
		)
		(fp_line
			(start -0.12065 0.2794)
			(end -0.12065 0.3048)
			(stroke
				(width 0.1)
				(type default)
			)
			(layer "F.Fab")
		)
		(fp_line
			(start -0.12065 -0.2794)
			(end 0.12065 -0.2794)
			(stroke
				(width 0.1)
				(type default)
			)
			(layer "F.Fab")
		)
		(fp_line
			(start -0.12065 -0.305054)
			(end -0.12065 -0.2794)
			(stroke
				(width 0.1)
				(type default)
			)
			(layer "F.Fab")
		)
		(fp_line
			(start -0.67945 0.3048)
			(end -0.67945 -0.305054)
			(stroke
				(width 0.1)
				(type default)
			)
			(layer "F.Fab")
		)
		(fp_line
			(start -0.67945 -0.305054)
			(end -0.12065 -0.305054)
			(stroke
				(width 0.1)
				(type default)
			)
			(layer "F.Fab")
		)
		(pad "1" smd circle
			(at -0.40005 0 180)
			(size 0 0)
			(layers "F.Cu" "F.Mask" "F.Paste")
			(net "PVDD18_S5_P1")
		)
		(pad "2" smd circle
			(at 0.40005 0 180)
			(size 0 0)
			(layers "F.Cu" "F.Mask" "F.Paste")
			(net "PVDDCR_CPU1_P1_OCP_N_R")
		)
	)
)
